# T6G (Grand Teton) — schematic netlist excerpt (pin names and nets, part order shuffled) for the footprints in the layout excerpt that follows; sources: Cadence DE-HDL packaged netlist, KiCad conversion of 04192023_DAF0TMB3IC0_F0TG_MB_C_brd_V02_OCP.brd

R3353  Q_RES  0 5% CHIP  pkg 0402LF  page 55 : A = CLK_100M_CPU1_CLK11_R_DN ; B = CLK_100M_CPU1_CLK11_DN
PC6639  Q_CAP  22UF 16V 20% X6S  pkg C0805  page 365 : A = SW_P12V_AUX_P0V9_RETIMER_CPU1_FLT ; B = GND
C6509  Q_CAP_DIFFBUS  DIFF BUS_0.22UF 6.3V 20% X6S  pkg C0201  page 275 : \1\ = P5E_CPU0_P0_TX_BUF_C_DP<4> ; \2\ = P5E_CPU0_P0_TX_BUF_DP<4>

(kicad_pcb
	(version 20260206)
	(generator "pcbnew")
	(generator_version "10.0")
	(general
		(thickness 1.6)
		(legacy_teardrops no)
	)
	(paper "A4")
	(title_block
		(title "04192023_DAF0TMB3IC0_F0TG_MB_C_brd_V02_OCP.brd")
		(comment 1 "Grand Teton / footprints 3244-3246 of 8354")
	)
	(layers
		(0 "F.Cu" signal "TOP")
		(4 "In1.Cu" signal "GND")
		(6 "In2.Cu" signal "IN1")
		(8 "In3.Cu" signal "GND1")
		(10 "In4.Cu" signal "IN2")
		(12 "In5.Cu" signal "GND2")
		(14 "In6.Cu" signal "IN3")
		(16 "In7.Cu" signal "GND3")
		(18 "In8.Cu" signal "VCC")
		(20 "In9.Cu" signal "VCC1")
		(22 "In10.Cu" signal "GND4")
		(24 "In11.Cu" signal "IN4")
		(26 "In12.Cu" signal "GND5")
		(28 "In13.Cu" signal "IN5")
		(30 "In14.Cu" signal "GND6")
		(32 "In15.Cu" signal "IN6")
		(34 "In16.Cu" signal "GND7")
		(2 "B.Cu" signal "BOTTOM")
		(9 "F.Adhes" user "F.Adhesive")
		(11 "B.Adhes" user "B.Adhesive")
		(13 "F.Paste" user "Package Geometry/Pastemask Top")
		(15 "B.Paste" user "Package Geometry/Pastemask Bottom")
		(5 "F.SilkS" user "Ref Des/Silkscreen Top")
		(7 "B.SilkS" user "Ref Des/Silkscreen Bottom")
		(1 "F.Mask" user "Board Geometry/Soldermask Top")
		(3 "B.Mask" user "Board Geometry/Soldermask Bottom")
		(17 "Dwgs.User" user "User.Drawings")
		(19 "Cmts.User" user "User.Comments")
		(21 "Eco1.User" user "User.Eco1")
		(23 "Eco2.User" user "User.Eco2")
		(25 "Edge.Cuts" user "Board Geometry/Outline")
		(27 "Margin" user)
		(31 "F.CrtYd" user "Package Geometry/Place Bound Top")
		(29 "B.CrtYd" user "Package Geometry/Place Bound Bottom")
		(35 "F.Fab" user "Ref Des/Assembly Top")
		(33 "B.Fab" user "Ref Des/Assembly Bottom")
	)
	(footprint ""
		(layer "F.Cu")
		(at 316.935866 -416.899344 -90)
		(property "Reference" "C6509"
			(at 0 0 270)
			(layer "F.SilkS")
			(hide yes)
			(effects
				(font
					(size 1.27 1.27)
				)
			)
		)
		(property "Value" ""
			(at 0 0 270)
			(layer "F.Fab")
			(effects
				(font
					(size 1.27 1.27)
				)
			)
		)
		(duplicate_pad_numbers_are_jumpers no)
		(fp_line
			(start -0.299974 0.150114)
			(end -0.299974 -0.150114)
			(stroke
				(width 0.1)
				(type default)
			)
			(layer "F.Fab")
		)
		(fp_line
			(start 0.299974 0.150114)
			(end -0.299974 0.150114)
			(stroke
				(width 0.1)
				(type default)
			)
			(layer "F.Fab")
		)
		(fp_line
			(start -0.299974 -0.150114)
			(end 0.299974 -0.150114)
			(stroke
				(width 0.1)
				(type default)
			)
			(layer "F.Fab")
		)
		(fp_line
			(start 0.299974 -0.150114)
			(end 0.299974 0.150114)
			(stroke
				(width 0.1)
				(type default)
			)
			(layer "F.Fab")
		)
		(pad "1" smd rect
			(at -0.2667 0 270)
			(size 0.3048 0.381)
			(layers "F.Cu" "F.Mask" "F.Paste")
			(net "P5E_CPU0_P0_TX_BUF_C_DP<4>")
		)
		(pad "2" smd rect
			(at 0.2667 0 270)
			(size 0.3048 0.381)
			(layers "F.Cu" "F.Mask" "F.Paste")
			(net "P5E_CPU0_P0_TX_BUF_DP<4>")
		)
	)
	(footprint ""
		(layer "F.Cu")
		(at 30.949392 -395.641576)
		(property "Reference" "PC6639"
			(at 0 0 0)
			(layer "F.SilkS")
			(hide yes)
			(effects
				(font
					(size 1.27 1.27)
				)
			)
		)
		(property "Value" ""
			(at 0 0 0)
			(layer "F.Fab")
			(effects
				(font
					(size 1.27 1.27)
				)
			)
		)
		(duplicate_pad_numbers_are_jumpers no)
		(fp_line
			(start -1.524 -0.762)
			(end 1.524 -0.762)
			(stroke
				(width 0.1524)
				(type default)
			)
			(layer "F.SilkS")
		)
		(fp_line
			(start -1.524 0.762)
			(end -1.524 -0.762)
			(stroke
				(width 0.1524)
				(type default)
			)
			(layer "F.SilkS")
		)
		(fp_line
			(start 1.524 -0.762)
			(end 1.524 0.762)
			(stroke
				(width 0.1524)
				(type default)
			)
			(layer "F.SilkS")
		)
		(fp_line
			(start 1.524 0.762)
			(end -1.524 0.762)
			(stroke
				(width 0.1524)
				(type default)
			)
			(layer "F.SilkS")
		)
		(fp_line
			(start -1.1049 -0.724916)
			(end -1.1049 0.724916)
			(stroke
				(width 0.1)
				(type default)
			)
			(layer "F.Fab")
		)
		(fp_line
			(start -1.1049 0.724916)
			(end 1.1049 0.724916)
			(stroke
				(width 0.1)
				(type default)
			)
			(layer "F.Fab")
		)
		(fp_line
			(start 1.1049 -0.724916)
			(end -1.1049 -0.724916)
			(stroke
				(width 0.1)
				(type default)
			)
			(layer "F.Fab")
		)
		(fp_line
			(start 1.1049 0.724916)
			(end 1.1049 -0.724916)
			(stroke
				(width 0.1)
				(type default)
			)
			(layer "F.Fab")
		)
		(pad "1" smd rect
			(at -0.889 0 180)
			(size 1.016 1.27)
			(layers "F.Cu" "F.Mask" "F.Paste")
			(net "SW_P12V_AUX_P0V9_RETIMER_CPU1_FLT")
		)
		(pad "2" smd rect
			(at 0.889 0 180)
			(size 1.016 1.27)
			(layers "F.Cu" "F.Mask" "F.Paste")
			(net "GND")
		)
	)
	(footprint ""
		(layer "F.Cu")
		(at 125.095 -321.655948 90)
		(property "Reference" "R3353"
			(at 0 0 90)
			(layer "F.SilkS")
			(hide yes)
			(effects
				(font
					(size 1.27 1.27)
				)
			)
		)
		(property "Value" ""
			(at 0 0 90)
			(layer "F.Fab")
			(effects
				(font
					(size 1.27 1.27)
				)
			)
		)
		(duplicate_pad_numbers_are_jumpers no)
		(fp_line
			(start 0.7874 -0.4064)
			(end 0.7874 0.0508)
			(stroke
				(width 0.1524)
				(type default)
			)
			(layer "F.SilkS")
		)
		(fp_line
			(start -0.7874 -0.4064)
			(end 0.7874 -0.4064)
			(stroke
				(width 0.1524)
				(type default)
			)
			(layer "F.SilkS")
		)
		(fp_line
			(start -0.7874 -0.0508)
			(end -0.7874 -0.4064)
			(stroke
				(width 0.1524)
				(type default)
			)
			(layer "F.SilkS")
		)
		(fp_line
			(start 0.390652 0.4064)
			(end -0.371348 0.4064)
			(stroke
				(width 0.1524)
				(type default)
			)
			(layer "F.SilkS")
		)
		(fp_line
			(start -0.12065 -0.305054)
			(end -0.12065 -0.2794)
			(stroke
				(width 0.1)
				(type default)
			)
			(layer "F.Fab")
		)
		(fp_line
			(start -0.67945 -0.305054)
			(end -0.12065 -0.305054)
			(stroke
				(width 0.1)
				(type default)
			)
			(layer "F.Fab")
		)
		(fp_line
			(start 0.67945 -0.3048)
			(end 0.67945 0.3048)
			(stroke
				(width 0.1)
				(type default)
			)
			(layer "F.Fab")
		)
		(fp_line
			(start 0.12065 -0.3048)
			(end 0.67945 -0.3048)
			(stroke
				(width 0.1)
				(type default)
			)
			(layer "F.Fab")
		)
		(fp_line
			(start 0.12065 -0.2794)
			(end 0.12065 -0.3048)
			(stroke
				(width 0.1)
				(type default)
			)
			(layer "F.Fab")
		)
		(fp_line
			(start -0.12065 -0.2794)
			(end 0.12065 -0.2794)
			(stroke
				(width 0.1)
				(type default)
			)
			(layer "F.Fab")
		)
		(fp_line
			(start 0.120396 0.2794)
			(end -0.12065 0.2794)
			(stroke
				(width 0.1)
				(type default)
			)
			(layer "F.Fab")
		)
		(fp_line
			(start -0.12065 0.2794)
			(end -0.12065 0.3048)
			(stroke
				(width 0.1)
				(type default)
			)
			(layer "F.Fab")
		)
		(fp_line
			(start 0.67945 0.3048)
			(end 0.120396 0.3048)
			(stroke
				(width 0.1)
				(type default)
			)
			(layer "F.Fab")
		)
		(fp_line
			(start 0.120396 0.3048)
			(end 0.120396 0.2794)
			(stroke
				(width 0.1)
				(type default)
			)
			(layer "F.Fab")
		)
		(fp_line
			(start -0.12065 0.3048)
			(end -0.67945 0.3048)
			(stroke
				(width 0.1)
				(type default)
			)
			(layer "F.Fab")
		)
		(fp_line
			(start -0.67945 0.3048)
			(end -0.67945 -0.305054)
			(stroke
				(width 0.1)
				(type default)
			)
			(layer "F.Fab")
		)
		(pad "1" smd circle
			(at -0.40005 0 90)
			(size 0 0)
			(layers "F.Cu" "F.Mask" "F.Paste")
			(net "CLK_100M_CPU1_CLK11_R_DN")
		)
		(pad "2" smd circle
			(at 0.40005 0 90)
			(size 0 0)
			(layers "F.Cu" "F.Mask" "F.Paste")
			(net "CLK_100M_CPU1_CLK11_DN")
		)
	)
)
